(kicad_pcb
	(version 20241229)
	(generator "pcbnew")
	(generator_version "9.0")
	(general
		(thickness 1.292)
		(legacy_teardrops no)
	)
	(paper "A4")
	(title_block
		(title "LPDDR5 Testbed")
		(date "2023-12-19")
		(rev "1.0.0")
		(comment 9 "footprints 108-113 of 160")
	)
	(layers
		(0 "F.Cu" signal)
		(4 "In1.Cu" power)
		(6 "In2.Cu" power)
		(8 "In3.Cu" signal)
		(10 "In4.Cu" signal)
		(2 "B.Cu" signal)
		(9 "F.Adhes" user "F.Adhesive")
		(11 "B.Adhes" user "B.Adhesive")
		(13 "F.Paste" user)
		(15 "B.Paste" user)
		(5 "F.SilkS" user "F.Silkscreen")
		(7 "B.SilkS" user "B.Silkscreen")
		(1 "F.Mask" user)
		(3 "B.Mask" user)
		(17 "Dwgs.User" user "User.Drawings")
		(19 "Cmts.User" user "User.Comments")
		(21 "Eco1.User" user "User.Eco1")
		(23 "Eco2.User" user "User.Eco2")
		(25 "Edge.Cuts" user)
		(27 "Margin" user)
		(31 "F.CrtYd" user "F.Courtyard")
		(29 "B.CrtYd" user "B.Courtyard")
		(35 "F.Fab" user)
		(33 "B.Fab" user)
	)
	(footprint "antmicro-footprints:C_0402_1005Metric"
		(layer "B.Cu")
		(at 131.275 82.45 180)
		(descr "Capacitor SMD 0402")
		(tags "capacitor SMD 0402")
		(property "Reference" "C46"
			(at -3.025 -0.45 0)
			(unlocked yes)
			(layer "B.SilkS")
			(effects
				(font
					(size 0.7 0.7)
					(thickness 0.15)
				)
				(justify left bottom mirror)
			)
		)
		(property "Value" "C_4u7_0402"
			(at -1.022927 -2.155213 0)
			(layer "B.Fab")
			(effects
				(font
					(size 0.7 0.7)
					(thickness 0.15)
				)
				(justify left bottom mirror)
			)
		)
		(property "Author" "Antmicro"
			(at 262.55 164.9 0)
			(layer "B.Fab")
			(hide yes)
			(effects
				(font
					(size 1 1)
					(thickness 0.15)
				)
				(justify mirror)
			)
		)
		(property "Dielectric" ""
			(at 262.55 164.9 0)
			(layer "B.Fab")
			(hide yes)
			(effects
				(font
					(size 1 1)
					(thickness 0.15)
				)
				(justify mirror)
			)
		)
		(property "License" "Apache-2.0"
			(at 262.55 164.9 0)
			(layer "B.Fab")
			(hide yes)
			(effects
				(font
					(size 1 1)
					(thickness 0.15)
				)
				(justify mirror)
			)
		)
		(property "MPN" "GRM155R61A475MEAAD"
			(at 262.55 164.9 0)
			(layer "B.Fab")
			(hide yes)
			(effects
				(font
					(size 1 1)
					(thickness 0.15)
				)
				(justify mirror)
			)
		)
		(property "Manufacturer" "Murata"
			(at 262.55 164.9 0)
			(layer "B.Fab")
			(hide yes)
			(effects
				(font
					(size 1 1)
					(thickness 0.15)
				)
				(justify mirror)
			)
		)
		(property "Val" "4u7"
			(at 262.55 164.9 0)
			(layer "B.Fab")
			(hide yes)
			(effects
				(font
					(size 1 1)
					(thickness 0.15)
				)
				(justify mirror)
			)
		)
		(property "Voltage" ""
			(at 262.55 164.9 0)
			(layer "B.Fab")
			(hide yes)
			(effects
				(font
					(size 1 1)
					(thickness 0.15)
				)
				(justify mirror)
			)
		)
		(sheetname "LPDDR5")
		(sheetfile "lpddr5.kicad_sch")
		(attr smd)
		(fp_rect
			(start -0.9659 0.481258)
			(end 0.9649 -0.458742)
			(stroke
				(width 0.05)
				(type solid)
			)
			(fill no)
			(layer "B.CrtYd")
		)
		(fp_line
			(start 0.499 0.25)
			(end 0.499 -0.248)
			(stroke
				(width 0.15)
				(type solid)
			)
			(layer "B.Fab")
		)
		(fp_line
			(start 0.499 -0.248)
			(end -0.499 -0.248)
			(stroke
				(width 0.15)
				(type solid)
			)
			(layer "B.Fab")
		)
		(fp_line
			(start -0.499 0.25)
			(end 0.499 0.25)
			(stroke
				(width 0.15)
				(type solid)
			)
			(layer "B.Fab")
		)
		(fp_line
			(start -0.499 -0.248)
			(end -0.499 0.25)
			(stroke
				(width 0.15)
				(type solid)
			)
			(layer "B.Fab")
		)
		(pad "1" smd roundrect
			(at -0.484 0 180)
			(size 0.59 0.64)
			(layers "B.Cu" "B.Mask" "B.Paste")
			(roundrect_rratio 0.25)
			(net 14 "GND")
			(pintype "passive")
		)
		(pad "2" smd roundrect
			(at 0.484 0 180)
			(size 0.59 0.64)
			(layers "B.Cu" "B.Mask" "B.Paste")
			(roundrect_rratio 0.25)
			(net 4 "+0V5")
			(pintype "passive")
		)
	)
	(footprint "antmicro-footprints:R_Array_4x0402_Panasonic_EXB28V"
		(layer "B.Cu")
		(at 162.7125 93.8)
		(property "Reference" "R73"
			(at -1.1 1.8 0)
			(unlocked yes)
			(layer "B.SilkS")
			(effects
				(font
					(size 0.7 0.7)
					(thickness 0.15)
				)
				(justify right bottom mirror)
			)
		)
		(property "Value" "R_4x100R_0402_array"
			(at -1.5 -2 0)
			(layer "B.Fab")
			(effects
				(font
					(size 0.7 0.7)
					(thickness 0.15)
				)
				(justify right bottom mirror)
			)
		)
		(property "Author" "Antmicro"
			(at 0 0 0)
			(layer "B.Fab")
			(hide yes)
			(effects
				(font
					(size 1 1)
					(thickness 0.15)
				)
				(justify mirror)
			)
		)
		(property "License" "Apache-2.0"
			(at 0 0 0)
			(layer "B.Fab")
			(hide yes)
			(effects
				(font
					(size 1 1)
					(thickness 0.15)
				)
				(justify mirror)
			)
		)
		(property "MPN" "EXB-28V101JX"
			(at 0 0 0)
			(layer "B.Fab")
			(hide yes)
			(effects
				(font
					(size 1 1)
					(thickness 0.15)
				)
				(justify mirror)
			)
		)
		(property "Manufacturer" "Panasonic"
			(at 0 0 0)
			(layer "B.Fab")
			(hide yes)
			(effects
				(font
					(size 1 1)
					(thickness 0.15)
				)
				(justify mirror)
			)
		)
		(property "Val" "R_4x100R_0402"
			(at 0 0 0)
			(layer "B.Fab")
			(hide yes)
			(effects
				(font
					(size 1 1)
					(thickness 0.15)
				)
				(justify mirror)
			)
		)
		(sheetname "Translators1")
		(sheetfile "translators.kicad_sch")
		(attr smd)
		(fp_line
			(start -1.25 0.5)
			(end -1.25 -0.498)
			(stroke
				(width 0.15)
				(type solid)
			)
			(layer "B.SilkS")
		)
		(fp_line
			(start 1.25 -0.499)
			(end 1.25 0.499)
			(stroke
				(width 0.15)
				(type solid)
			)
			(layer "B.SilkS")
		)
		(fp_rect
			(start -1.25 0.8)
			(end 1.25 -0.8)
			(stroke
				(width 0.05)
				(type solid)
			)
			(fill no)
			(layer "B.CrtYd")
		)
		(fp_line
			(start -1 -0.498)
			(end -1 0.5)
			(stroke
				(width 0.15)
				(type solid)
			)
			(layer "B.Fab")
		)
		(fp_line
			(start -1 0.5)
			(end 0.998 0.5)
			(stroke
				(width 0.15)
				(type solid)
			)
			(layer "B.Fab")
		)
		(fp_line
			(start 0.998 -0.498)
			(end -1 -0.498)
			(stroke
				(width 0.15)
				(type solid)
			)
			(layer "B.Fab")
		)
		(fp_line
			(start 0.998 0.5)
			(end 0.998 -0.498)
			(stroke
				(width 0.15)
				(type solid)
			)
			(layer "B.Fab")
		)
		(pad "1" smd roundrect
			(at -0.8875 -0.45)
			(size 0.525 0.5)
			(layers "B.Cu" "B.Mask" "B.Paste")
			(roundrect_rratio 0.25)
			(net 219 "/LPDDR5/LPDDR5_B.DQ5")
			(pinfunction "R1.1")
			(pintype "passive")
		)
		(pad "2" smd roundrect
			(at -0.25 -0.45)
			(size 0.25 0.5)
			(layers "B.Cu" "B.Mask" "B.Paste")
			(roundrect_rratio 0.25)
			(net 220 "/LPDDR5/LPDDR5_B.DQ4")
			(pinfunction "R2.1")
			(pintype "passive")
		)
		(pad "3" smd roundrect
			(at 0.25 -0.45)
			(size 0.25 0.5)
			(layers "B.Cu" "B.Mask" "B.Paste")
			(roundrect_rratio 0.25)
			(net 218 "/LPDDR5/LPDDR5_B.DQ6")
			(pinfunction "R3.1")
			(pintype "passive")
		)
		(pad "4" smd roundrect
			(at 0.8875 -0.45)
			(size 0.525 0.5)
			(layers "B.Cu" "B.Mask" "B.Paste")
			(roundrect_rratio 0.25)
			(net 217 "/LPDDR5/LPDDR5_B.DQ7")
			(pinfunction "R4.1")
			(pintype "passive")
		)
		(pad "5" smd roundrect
			(at 0.8875 0.45)
			(size 0.525 0.5)
			(layers "B.Cu" "B.Mask" "B.Paste")
			(roundrect_rratio 0.25)
			(net 14 "GND")
			(pinfunction "R4.2")
			(pintype "passive")
		)
		(pad "6" smd roundrect
			(at 0.25 0.45)
			(size 0.25 0.5)
			(layers "B.Cu" "B.Mask" "B.Paste")
			(roundrect_rratio 0.25)
			(net 14 "GND")
			(pinfunction "R3.2")
			(pintype "passive")
		)
		(pad "7" smd roundrect
			(at -0.25 0.45)
			(size 0.25 0.5)
			(layers "B.Cu" "B.Mask" "B.Paste")
			(roundrect_rratio 0.25)
			(net 14 "GND")
			(pinfunction "R2.2")
			(pintype "passive")
		)
		(pad "8" smd roundrect
			(at -0.8875 0.45)
			(size 0.525 0.5)
			(layers "B.Cu" "B.Mask" "B.Paste")
			(roundrect_rratio 0.25)
			(net 14 "GND")
			(pinfunction "R1.2")
			(pintype "passive")
		)
	)
	(footprint "antmicro-footprints:C_0402_1005Metric"
		(layer "B.Cu")
		(at 138.275 82.45)
		(descr "Capacitor SMD 0402")
		(tags "capacitor SMD 0402")
		(property "Reference" "C48"
			(at 0.925 0.45 0)
			(unlocked yes)
			(layer "B.SilkS")
			(effects
				(font
					(size 0.7 0.7)
					(thickness 0.15)
				)
				(justify right bottom mirror)
			)
		)
		(property "Value" "C_4u7_0402"
			(at -1.022927 -2.155213 0)
			(layer "B.Fab")
			(effects
				(font
					(size 0.7 0.7)
					(thickness 0.15)
				)
				(justify right bottom mirror)
			)
		)
		(property "Author" "Antmicro"
			(at 0 0 0)
			(layer "B.Fab")
			(hide yes)
			(effects
				(font
					(size 1 1)
					(thickness 0.15)
				)
				(justify mirror)
			)
		)
		(property "Dielectric" ""
			(at 0 0 0)
			(layer "B.Fab")
			(hide yes)
			(effects
				(font
					(size 1 1)
					(thickness 0.15)
				)
				(justify mirror)
			)
		)
		(property "License" "Apache-2.0"
			(at 0 0 0)
			(layer "B.Fab")
			(hide yes)
			(effects
				(font
					(size 1 1)
					(thickness 0.15)
				)
				(justify mirror)
			)
		)
		(property "MPN" "GRM155R61A475MEAAD"
			(at 0 0 0)
			(layer "B.Fab")
			(hide yes)
			(effects
				(font
					(size 1 1)
					(thickness 0.15)
				)
				(justify mirror)
			)
		)
		(property "Manufacturer" "Murata"
			(at 0 0 0)
			(layer "B.Fab")
			(hide yes)
			(effects
				(font
					(size 1 1)
					(thickness 0.15)
				)
				(justify mirror)
			)
		)
		(property "Val" "4u7"
			(at 0 0 0)
			(layer "B.Fab")
			(hide yes)
			(effects
				(font
					(size 1 1)
					(thickness 0.15)
				)
				(justify mirror)
			)
		)
		(property "Voltage" ""
			(at 0 0 0)
			(layer "B.Fab")
			(hide yes)
			(effects
				(font
					(size 1 1)
					(thickness 0.15)
				)
				(justify mirror)
			)
		)
		(sheetname "LPDDR5")
		(sheetfile "lpddr5.kicad_sch")
		(attr smd)
		(fp_rect
			(start -0.9659 0.481258)
			(end 0.9649 -0.458742)
			(stroke
				(width 0.05)
				(type solid)
			)
			(fill no)
			(layer "B.CrtYd")
		)
		(fp_line
			(start -0.499 -0.248)
			(end -0.499 0.25)
			(stroke
				(width 0.15)
				(type solid)
			)
			(layer "B.Fab")
		)
		(fp_line
			(start -0.499 0.25)
			(end 0.499 0.25)
			(stroke
				(width 0.15)
				(type solid)
			)
			(layer "B.Fab")
		)
		(fp_line
			(start 0.499 -0.248)
			(end -0.499 -0.248)
			(stroke
				(width 0.15)
				(type solid)
			)
			(layer "B.Fab")
		)
		(fp_line
			(start 0.499 0.25)
			(end 0.499 -0.248)
			(stroke
				(width 0.15)
				(type solid)
			)
			(layer "B.Fab")
		)
		(pad "1" smd roundrect
			(at -0.484 0)
			(size 0.59 0.64)
			(layers "B.Cu" "B.Mask" "B.Paste")
			(roundrect_rratio 0.25)
			(net 14 "GND")
			(pintype "passive")
		)
		(pad "2" smd roundrect
			(at 0.484 0)
			(size 0.59 0.64)
			(layers "B.Cu" "B.Mask" "B.Paste")
			(roundrect_rratio 0.25)
			(net 4 "+0V5")
			(pintype "passive")
		)
	)
	(footprint "antmicro-footprints:R_Array_4x0402_Panasonic_EXB28V"
		(layer "B.Cu")
		(at 127.7 93.8)
		(property "Reference" "R21"
			(at 1.1 -1.3 0)
			(unlocked yes)
			(layer "B.SilkS")
			(effects
				(font
					(size 0.7 0.7)
					(thickness 0.15)
				)
				(justify left bottom mirror)
			)
		)
		(property "Value" "R_4x100R_0402_array"
			(at -1.5 -2 180)
			(layer "B.Fab")
			(effects
				(font
					(size 0.7 0.7)
					(thickness 0.15)
				)
				(justify left bottom mirror)
			)
		)
		(property "Author" "Antmicro"
			(at 0 0 0)
			(layer "B.Fab")
			(hide yes)
			(effects
				(font
					(size 1 1)
					(thickness 0.15)
				)
				(justify mirror)
			)
		)
		(property "License" "Apache-2.0"
			(at 0 0 0)
			(layer "B.Fab")
			(hide yes)
			(effects
				(font
					(size 1 1)
					(thickness 0.15)
				)
				(justify mirror)
			)
		)
		(property "MPN" "EXB-28V101JX"
			(at 0 0 0)
			(layer "B.Fab")
			(hide yes)
			(effects
				(font
					(size 1 1)
					(thickness 0.15)
				)
				(justify mirror)
			)
		)
		(property "Manufacturer" "Panasonic"
			(at 0 0 0)
			(layer "B.Fab")
			(hide yes)
			(effects
				(font
					(size 1 1)
					(thickness 0.15)
				)
				(justify mirror)
			)
		)
		(property "Val" "R_4x100R_0402"
			(at 0 0 0)
			(layer "B.Fab")
			(hide yes)
			(effects
				(font
					(size 1 1)
					(thickness 0.15)
				)
				(justify mirror)
			)
		)
		(sheetname "Translators")
		(sheetfile "translators.kicad_sch")
		(attr smd)
		(fp_line
			(start -1.25 0.5)
			(end -1.25 -0.498)
			(stroke
				(width 0.15)
				(type solid)
			)
			(layer "B.SilkS")
		)
		(fp_line
			(start 1.25 -0.499)
			(end 1.25 0.499)
			(stroke
				(width 0.15)
				(type solid)
			)
			(layer "B.SilkS")
		)
		(fp_rect
			(start -1.25 0.8)
			(end 1.25 -0.8)
			(stroke
				(width 0.05)
				(type solid)
			)
			(fill no)
			(layer "B.CrtYd")
		)
		(fp_line
			(start -1 -0.498)
			(end -1 0.5)
			(stroke
				(width 0.15)
				(type solid)
			)
			(layer "B.Fab")
		)
		(fp_line
			(start -1 0.5)
			(end 0.998 0.5)
			(stroke
				(width 0.15)
				(type solid)
			)
			(layer "B.Fab")
		)
		(fp_line
			(start 0.998 -0.498)
			(end -1 -0.498)
			(stroke
				(width 0.15)
				(type solid)
			)
			(layer "B.Fab")
		)
		(fp_line
			(start 0.998 0.5)
			(end 0.998 -0.498)
			(stroke
				(width 0.15)
				(type solid)
			)
			(layer "B.Fab")
		)
		(pad "1" smd roundrect
			(at -0.8875 -0.45)
			(size 0.525 0.5)
			(layers "B.Cu" "B.Mask" "B.Paste")
			(roundrect_rratio 0.25)
			(net 43 "/LPDDR5/LPDDR5_A.CS0")
			(pinfunction "R1.1")
			(pintype "passive")
		)
		(pad "2" smd roundrect
			(at -0.25 -0.45)
			(size 0.25 0.5)
			(layers "B.Cu" "B.Mask" "B.Paste")
			(roundrect_rratio 0.25)
			(net 44 "/LPDDR5/LPDDR5_A.CS1")
			(pinfunction "R2.1")
			(pintype "passive")
		)
		(pad "3" smd roundrect
			(at 0.25 -0.45)
			(size 0.25 0.5)
			(layers "B.Cu" "B.Mask" "B.Paste")
			(roundrect_rratio 0.25)
			(net 57 "/LPDDR5/LPDDR5_A.CA0")
			(pinfunction "R3.1")
			(pintype "passive")
		)
		(pad "4" smd roundrect
			(at 0.8875 -0.45)
			(size 0.525 0.5)
			(layers "B.Cu" "B.Mask" "B.Paste")
			(roundrect_rratio 0.25)
			(net 58 "/LPDDR5/LPDDR5_A.CA1")
			(pinfunction "R4.1")
			(pintype "passive")
		)
		(pad "5" smd roundrect
			(at 0.8875 0.45)
			(size 0.525 0.5)
			(layers "B.Cu" "B.Mask" "B.Paste")
			(roundrect_rratio 0.25)
			(net 14 "GND")
			(pinfunction "R4.2")
			(pintype "passive")
		)
		(pad "6" smd roundrect
			(at 0.25 0.45)
			(size 0.25 0.5)
			(layers "B.Cu" "B.Mask" "B.Paste")
			(roundrect_rratio 0.25)
			(net 14 "GND")
			(pinfunction "R3.2")
			(pintype "passive")
		)
		(pad "7" smd roundrect
			(at -0.25 0.45)
			(size 0.25 0.5)
			(layers "B.Cu" "B.Mask" "B.Paste")
			(roundrect_rratio 0.25)
			(net 14 "GND")
			(pinfunction "R2.2")
			(pintype "passive")
		)
		(pad "8" smd roundrect
			(at -0.8875 0.45)
			(size 0.525 0.5)
			(layers "B.Cu" "B.Mask" "B.Paste")
			(roundrect_rratio 0.25)
			(net 14 "GND")
			(pinfunction "R1.2")
			(pintype "passive")
		)
	)
	(footprint "antmicro-footprints:R_0402_1005Metric"
		(layer "B.Cu")
		(at 105.17 91.95 180)
		(descr "Resistor SMD 0402")
		(tags "resistor SMD 0402")
		(property "Reference" "R85"
			(at 1.07 -0.35 0)
			(unlocked yes)
			(layer "B.SilkS")
			(effects
				(font
					(size 0.7 0.7)
					(thickness 0.15)
				)
				(justify left bottom mirror)
			)
		)
		(property "Value" "R_100R_0402"
			(at -1.011843 -1.772047 0)
			(layer "B.Fab")
			(effects
				(font
					(size 0.7 0.7)
					(thickness 0.15)
				)
				(justify left bottom mirror)
			)
		)
		(property "Author" "Antmicro"
			(at 210.34 183.9 0)
			(layer "B.Fab")
			(hide yes)
			(effects
				(font
					(size 1 1)
					(thickness 0.15)
				)
				(justify mirror)
			)
		)
		(property "License" "Apache-2.0"
			(at 210.34 183.9 0)
			(layer "B.Fab")
			(hide yes)
			(effects
				(font
					(size 1 1)
					(thickness 0.15)
				)
				(justify mirror)
			)
		)
		(property "MPN" "CR0402-FX-1000GLF"
			(at 210.34 183.9 0)
			(layer "B.Fab")
			(hide yes)
			(effects
				(font
					(size 1 1)
					(thickness 0.15)
				)
				(justify mirror)
			)
		)
		(property "Manufacturer" "Bourns"
			(at 210.34 183.9 0)
			(layer "B.Fab")
			(hide yes)
			(effects
				(font
					(size 1 1)
					(thickness 0.15)
				)
				(justify mirror)
			)
		)
		(property "Tolerance" "1%"
			(at 210.34 183.9 0)
			(layer "B.Fab")
			(hide yes)
			(effects
				(font
					(size 1 1)
					(thickness 0.15)
				)
				(justify mirror)
			)
		)
		(property "Val" "100R"
			(at 210.34 183.9 0)
			(layer "B.Fab")
			(hide yes)
			(effects
				(font
					(size 1 1)
					(thickness 0.15)
				)
				(justify mirror)
			)
		)
		(sheetname "Translators")
		(sheetfile "translators.kicad_sch")
		(attr smd)
		(fp_rect
			(start -0.93 0.47)
			(end 0.93 -0.47)
			(stroke
				(width 0.05)
				(type solid)
			)
			(fill no)
			(layer "B.CrtYd")
		)
		(fp_rect
			(start -0.5 0.25)
			(end 0.5 -0.25)
			(stroke
				(width 0.15)
				(type solid)
			)
			(fill no)
			(layer "B.Fab")
		)
		(pad "1" smd roundrect
			(at -0.485 0 180)
			(size 0.59 0.64)
			(layers "B.Cu" "B.Mask" "B.Paste")
			(roundrect_rratio 0.25)
			(net 190 "/LPDDR5/LPDDR5_A.DMI1")
			(pintype "passive")
		)
		(pad "2" smd roundrect
			(at 0.485 0 180)
			(size 0.59 0.64)
			(layers "B.Cu" "B.Mask" "B.Paste")
			(roundrect_rratio 0.25)
			(net 14 "GND")
			(pintype "passive")
		)
	)
	(footprint "antmicro-footprints:C_0402_1005Metric"
		(layer "B.Cu")
		(at 129.175 86.15 180)
		(descr "Capacitor SMD 0402")
		(tags "capacitor SMD 0402")
		(property "Reference" "C35"
			(at 0.875 -0.35 0)
			(unlocked yes)
			(layer "B.SilkS")
			(effects
				(font
					(size 0.7 0.7)
					(thickness 0.15)
				)
				(justify left bottom mirror)
			)
		)
		(property "Value" "C_4u7_0402"
			(at -1.022927 -2.155213 0)
			(layer "B.Fab")
			(effects
				(font
					(size 0.7 0.7)
					(thickness 0.15)
				)
				(justify left bottom mirror)
			)
		)
		(property "Author" "Antmicro"
			(at 258.35 172.3 0)
			(layer "B.Fab")
			(hide yes)
			(effects
				(font
					(size 1 1)
					(thickness 0.15)
				)
				(justify mirror)
			)
		)
		(property "Dielectric" ""
			(at 258.35 172.3 0)
			(layer "B.Fab")
			(hide yes)
			(effects
				(font
					(size 1 1)
					(thickness 0.15)
				)
				(justify mirror)
			)
		)
		(property "License" "Apache-2.0"
			(at 258.35 172.3 0)
			(layer "B.Fab")
			(hide yes)
			(effects
				(font
					(size 1 1)
					(thickness 0.15)
				)
				(justify mirror)
			)
		)
		(property "MPN" "GRM155R61A475MEAAD"
			(at 258.35 172.3 0)
			(layer "B.Fab")
			(hide yes)
			(effects
				(font
					(size 1 1)
					(thickness 0.15)
				)
				(justify mirror)
			)
		)
		(property "Manufacturer" "Murata"
			(at 258.35 172.3 0)
			(layer "B.Fab")
			(hide yes)
			(effects
				(font
					(size 1 1)
					(thickness 0.15)
				)
				(justify mirror)
			)
		)
		(property "Val" "4u7"
			(at 258.35 172.3 0)
			(layer "B.Fab")
			(hide yes)
			(effects
				(font
					(size 1 1)
					(thickness 0.15)
				)
				(justify mirror)
			)
		)
		(property "Voltage" ""
			(at 258.35 172.3 0)
			(layer "B.Fab")
			(hide yes)
			(effects
				(font
					(size 1 1)
					(thickness 0.15)
				)
				(justify mirror)
			)
		)
		(sheetname "LPDDR5")
		(sheetfile "lpddr5.kicad_sch")
		(attr smd)
		(fp_rect
			(start -0.9659 0.481258)
			(end 0.9649 -0.458742)
			(stroke
				(width 0.05)
				(type solid)
			)
			(fill no)
			(layer "B.CrtYd")
		)
		(fp_line
			(start 0.499 0.25)
			(end 0.499 -0.248)
			(stroke
				(width 0.15)
				(type solid)
			)
			(layer "B.Fab")
		)
		(fp_line
			(start 0.499 -0.248)
			(end -0.499 -0.248)
			(stroke
				(width 0.15)
				(type solid)
			)
			(layer "B.Fab")
		)
		(fp_line
			(start -0.499 0.25)
			(end 0.499 0.25)
			(stroke
				(width 0.15)
				(type solid)
			)
			(layer "B.Fab")
		)
		(fp_line
			(start -0.499 -0.248)
			(end -0.499 0.25)
			(stroke
				(width 0.15)
				(type solid)
			)
			(layer "B.Fab")
		)
		(pad "1" smd roundrect
			(at -0.484 0 180)
			(size 0.59 0.64)
			(layers "B.Cu" "B.Mask" "B.Paste")
			(roundrect_rratio 0.25)
			(net 14 "GND")
			(pintype "passive")
		)
		(pad "2" smd roundrect
			(at 0.484 0 180)
			(size 0.59 0.64)
			(layers "B.Cu" "B.Mask" "B.Paste")
			(roundrect_rratio 0.25)
			(net 35 "+1V8")
			(pintype "passive")
		)
	)
)
